# BASEBOARD_FAB2 (Tioga Pass) — schematic netlist excerpt (pin names and nets, part order shuffled) for the footprints in the layout excerpt that follows; sources: Cadence DE-HDL packaged netlist, KiCad conversion of Wiwynn_Tioga_Pass_MB.brd

Q1D1  FET_N_DUAL  2N7002DW FET  pkg SMLF  page 199
  SOURCE(0)  = AGND_HSC
  GATE(0)  = A_HSC_LOW_EN
  DRAIN(0)  = A_HSC_ISET_S
  SOURCE(0)  = AGND_HSC
  GATE(0)  = A_HSC_HIGH_EN
  DRAIN(0)  = A_HSC_ISET_S2

T1D8  TEST-PAD-12P-1-GP-U  pkg DISCRET-GB1  page 257
  DP  = L10_85OHM_5INCH_DN
  DN  = L10_85OHM_5INCH_DP
  GND(0)  = GND
  GND(1)  = GND
  GND(2)  = GND
  GND(3)  = GND
  GND(4)  = GND
  GND(5)  = GND
  GND(6)  = GND
  GND(7)  = GND
  GND(8)  = GND
  GND(9)  = GND

(kicad_pcb
	(version 20260206)
	(generator "pcbnew")
	(generator_version "10.0")
	(general
		(thickness 1.6)
		(legacy_teardrops no)
	)
	(paper "A4")
	(title_block
		(title "Wiwynn_Tioga_Pass_MB.brd")
		(comment 1 "Tioga Pass / footprints 1566-1567 of 4770")
	)
	(layers
		(0 "F.Cu" signal "TOP")
		(4 "In1.Cu" signal "L2GND")
		(6 "In2.Cu" signal "L3")
		(8 "In3.Cu" signal "L4GND")
		(10 "In4.Cu" signal "L5")
		(12 "In5.Cu" signal "L6GND")
		(14 "In6.Cu" signal "L7VCC")
		(16 "In7.Cu" signal "L8VCC")
		(18 "In8.Cu" signal "L9GND")
		(20 "In9.Cu" signal "L10")
		(22 "In10.Cu" signal "L11GND")
		(24 "In11.Cu" signal "L12")
		(26 "In12.Cu" signal "L13GND")
		(2 "B.Cu" signal "BOTTOM")
		(9 "F.Adhes" user "F.Adhesive")
		(11 "B.Adhes" user "B.Adhesive")
		(13 "F.Paste" user "Package Geometry/Pastemask Top")
		(15 "B.Paste" user "Package Geometry/Pastemask Bottom")
		(5 "F.SilkS" user "Ref Des/Silkscreen Top")
		(7 "B.SilkS" user "Ref Des/Silkscreen Bottom")
		(1 "F.Mask" user "Board Geometry/Soldermask Top")
		(3 "B.Mask" user "Board Geometry/Soldermask Bottom")
		(17 "Dwgs.User" user "User.Drawings")
		(19 "Cmts.User" user "User.Comments")
		(21 "Eco1.User" user "User.Eco1")
		(23 "Eco2.User" user "User.Eco2")
		(25 "Edge.Cuts" user "Board Geometry/Outline")
		(27 "Margin" user)
		(31 "F.CrtYd" user "Package Geometry/Place Bound Top")
		(29 "B.CrtYd" user "Package Geometry/Place Bound Bottom")
		(35 "F.Fab" user "Ref Des/Assembly Top")
		(33 "B.Fab" user "Ref Des/Assembly Bottom")
	)
	(footprint ""
		(layer "F.Cu")
		(at 149.065488 -164.91712 90)
		(property "Reference" "T1D8"
			(at 0 0 90)
			(layer "F.SilkS")
			(hide yes)
			(effects
				(font
					(size 1.27 1.27)
				)
			)
		)
		(property "Value" "*"
			(at -3.4036 -4.46405 90)
			(unlocked yes)
			(layer "F.Fab")
			(hide yes)
			(effects
				(font
					(size 0.889 0.889)
					(thickness 0.1524)
				)
			)
		)
		(property "Device Type" "TEST-PAD-12P-1-GP-U_DISCRET-GBA"
			(at -3.4036 -5.98805 90)
			(unlocked yes)
			(layer "F.Fab")
			(hide yes)
			(effects
				(font
					(size 0.889 0.889)
					(thickness 0.1524)
				)
			)
		)
		(duplicate_pad_numbers_are_jumpers no)
		(fp_line
			(start 2.3622 -4.826)
			(end 2.3622 3.4798)
			(stroke
				(width 0.1524)
				(type default)
			)
			(layer "F.SilkS")
		)
		(fp_line
			(start -2.3876 -4.826)
			(end 2.3622 -4.826)
			(stroke
				(width 0.1524)
				(type default)
			)
			(layer "F.SilkS")
		)
		(fp_line
			(start 2.3622 3.4798)
			(end -2.3876 3.4798)
			(stroke
				(width 0.1524)
				(type default)
			)
			(layer "F.SilkS")
		)
		(fp_line
			(start -2.3876 3.4798)
			(end -2.3876 -4.826)
			(stroke
				(width 0.1524)
				(type default)
			)
			(layer "F.SilkS")
		)
		(fp_rect
			(start -2.6416 3.7338)
			(end 2.6162 -5.08)
			(stroke
				(width 0)
				(type default)
			)
			(fill no)
			(layer "F.CrtYd")
		)
		(fp_rect
			(start -2.6416 3.7338)
			(end 2.6162 -5.08)
			(stroke
				(width 0)
				(type default)
			)
			(fill no)
			(layer "F.Fab")
		)
		(pad "1" smd circle
			(at 0.496824 -1.301496 90)
			(size 0.6604 0.6604)
			(layers "F.Cu" "F.Mask" "F.Paste")
			(net "L10_85OHM_5INCH_DN")
		)
		(pad "2" smd circle
			(at -0.503936 -1.301496 90)
			(size 0.6604 0.6604)
			(layers "F.Cu" "F.Mask" "F.Paste")
			(net "L10_85OHM_5INCH_DP")
		)
		(pad "3" smd custom
			(at -0.00889 0.370078 90)
			(size 0.74295 0.74295)
			(layers "F.Cu" "F.Mask" "F.Paste")
			(net "GND")
			(options
				(clearance outline)
				(anchor circle)
			)
			(primitives
				(gr_poly
					(pts
						(xy -2.1209 1.4859) (xy 2.1209 1.4859) (xy 2.1209 -1.4859) (xy 1.08585 -1.4859) (xy 1.08585 -0.4699)
						(xy -1.08585 -0.4699) (xy -1.08585 -1.4859) (xy -2.1209 -1.4859)
					)
					(width 0)
					(fill yes)
				)
			)
		)
		(pad "4" thru_hole circle
			(at 1.266444 -3.851656 90)
			(size 1.4478 1.4478)
			(drill 1.0414)
			(layers "*.Cu" "*.Mask")
			(remove_unused_layers no)
			(net "GND")
			(clearance 0.1524)
			(thermal_gap 0.1524)
		)
		(pad "5" thru_hole circle
			(at -1.273556 -3.851656 90)
			(size 1.4478 1.4478)
			(drill 1.0414)
			(layers "*.Cu" "*.Mask")
			(remove_unused_layers no)
			(net "GND")
			(clearance 0.1524)
			(thermal_gap 0.1524)
		)
		(pad "6" thru_hole circle
			(at 1.266444 2.498344 90)
			(size 1.4478 1.4478)
			(drill 1.0414)
			(layers "*.Cu" "*.Mask")
			(remove_unused_layers no)
			(net "GND")
			(clearance 0.1524)
			(thermal_gap 0.1524)
		)
		(pad "7" thru_hole circle
			(at -1.273556 2.498344 90)
			(size 1.4478 1.4478)
			(drill 1.0414)
			(layers "*.Cu" "*.Mask")
			(remove_unused_layers no)
			(net "GND")
			(clearance 0.1524)
			(thermal_gap 0.1524)
		)
		(pad "8" thru_hole circle
			(at 1.27 -0.4572 90)
			(size 0.7112 0.7112)
			(drill 0.4064)
			(layers "*.Cu" "*.Mask")
			(remove_unused_layers no)
			(net "GND")
			(clearance 0.1016)
			(thermal_gap 0.1016)
		)
		(pad "9" thru_hole circle
			(at 1.27 0.762 90)
			(size 0.7112 0.7112)
			(drill 0.4064)
			(layers "*.Cu" "*.Mask")
			(remove_unused_layers no)
			(net "GND")
			(clearance 0.1016)
			(thermal_gap 0.1016)
		)
		(pad "10" thru_hole circle
			(at -0.0254 0.762 90)
			(size 0.7112 0.7112)
			(drill 0.4064)
			(layers "*.Cu" "*.Mask")
			(remove_unused_layers no)
			(net "GND")
			(clearance 0.1016)
			(thermal_gap 0.1016)
		)
		(pad "11" thru_hole circle
			(at -1.27 0.762 90)
			(size 0.7112 0.7112)
			(drill 0.4064)
			(layers "*.Cu" "*.Mask")
			(remove_unused_layers no)
			(net "GND")
			(clearance 0.1016)
			(thermal_gap 0.1016)
		)
		(pad "12" thru_hole circle
			(at -1.27 -0.4572 90)
			(size 0.7112 0.7112)
			(drill 0.4064)
			(layers "*.Cu" "*.Mask")
			(remove_unused_layers no)
			(net "GND")
			(clearance 0.1016)
			(thermal_gap 0.1016)
		)
	)
	(footprint ""
		(layer "F.Cu")
		(at 17.399 -84.455 -90)
		(property "Reference" "Q1D1"
			(at 2.94767 1.905 0)
			(unlocked yes)
			(layer "F.SilkS")
			(effects
				(font
					(size 0.7874 0.5842)
					(thickness 0.1524)
				)
				(justify left)
			)
		)
		(property "Value" ""
			(at 0 0 270)
			(layer "F.Fab")
			(effects
				(font
					(size 1.27 1.27)
				)
			)
		)
		(duplicate_pad_numbers_are_jumpers no)
		(fp_circle
			(center -0.848614 -0.6477)
			(end -0.848614 -0.7747)
			(stroke
				(width 0.254)
				(type default)
			)
			(fill no)
			(layer "F.SilkS")
		)
		(fp_poly
			(pts
				(xy 0.21463 -0.450088) (xy 1.56337 -0.450088) (xy 1.56337 1.75006) (xy 0.21463 1.75006)
			)
			(stroke
				(width 0)
				(type default)
			)
			(fill no)
			(layer "F.CrtYd")
		)
		(fp_line
			(start 0.21463 1.75006)
			(end 0.21463 -0.450088)
			(stroke
				(width 0.1)
				(type default)
			)
			(layer "F.Fab")
		)
		(fp_line
			(start 1.56337 1.75006)
			(end 0.21463 1.75006)
			(stroke
				(width 0.1)
				(type default)
			)
			(layer "F.Fab")
		)
		(fp_line
			(start 0.21463 -0.450088)
			(end 1.56337 -0.450088)
			(stroke
				(width 0.1)
				(type default)
			)
			(layer "F.Fab")
		)
		(fp_line
			(start 1.56337 -0.450088)
			(end 1.56337 1.75006)
			(stroke
				(width 0.1)
				(type default)
			)
			(layer "F.Fab")
		)
		(fp_circle
			(center -0.848614 -0.6477)
			(end -0.848614 -0.7747)
			(stroke
				(width 0.254)
				(type default)
			)
			(fill no)
			(layer "F.Fab")
		)
		(pad "1" smd rect
			(at 0 0 270)
			(size 1.016 0.381)
			(layers "F.Cu" "F.Mask" "F.Paste")
			(net "AGND_HSC")
		)
		(pad "2" smd rect
			(at 0 0.649986 270)
			(size 1.016 0.381)
			(layers "F.Cu" "F.Mask" "F.Paste")
			(net "A_HSC_LOW_EN")
		)
		(pad "3" smd rect
			(at 0 1.299972 270)
			(size 1.016 0.381)
			(layers "F.Cu" "F.Mask" "F.Paste")
			(net "A_HSC_ISET_S")
		)
		(pad "4" smd rect
			(at 1.778 1.299972 270)
			(size 1.016 0.381)
			(layers "F.Cu" "F.Mask" "F.Paste")
			(net "AGND_HSC")
		)
		(pad "5" smd rect
			(at 1.778 0.649986 270)
			(size 1.016 0.381)
			(layers "F.Cu" "F.Mask" "F.Paste")
			(net "A_HSC_HIGH_EN")
		)
		(pad "6" smd rect
			(at 1.778 0 270)
			(size 1.016 0.381)
			(layers "F.Cu" "F.Mask" "F.Paste")
			(net "A_HSC_ISET_S2")
		)
	)
)
